# T6G (Grand Teton) — schematic netlist excerpt (pin names and nets, part order shuffled) for the footprints in the layout excerpt that follows; sources: Cadence DE-HDL packaged netlist, KiCad conversion of 04192023_DAF0TMB3IC0_F0TG_MB_C_brd_V02_OCP.brd

C411  Q_CAP  0.1UF 10V 10% X7S  pkg C0201  page 345 : A = P0V9_CPU1_RT2_2A ; B = GND
R3211  Q_RES  22 1% EMPTY  pkg 0402LF  page 138 : A = NCSI_BMC_RXD0_R1 ; B = RMII_OCP_BMC_RXD_0
C2137  Q_CAP  22UF 4V 20% X6S  pkg C0402  page 68 : A = PVDD11_S3_P0 ; B = GND

(kicad_pcb
	(version 20260206)
	(generator "pcbnew")
	(generator_version "10.0")
	(general
		(thickness 1.6)
		(legacy_teardrops no)
	)
	(paper "A4")
	(title_block
		(title "04192023_DAF0TMB3IC0_F0TG_MB_C_brd_V02_OCP.brd")
		(comment 1 "Grand Teton / footprints 7233-7235 of 8354")
	)
	(layers
		(0 "F.Cu" signal "TOP")
		(4 "In1.Cu" signal "GND")
		(6 "In2.Cu" signal "IN1")
		(8 "In3.Cu" signal "GND1")
		(10 "In4.Cu" signal "IN2")
		(12 "In5.Cu" signal "GND2")
		(14 "In6.Cu" signal "IN3")
		(16 "In7.Cu" signal "GND3")
		(18 "In8.Cu" signal "VCC")
		(20 "In9.Cu" signal "VCC1")
		(22 "In10.Cu" signal "GND4")
		(24 "In11.Cu" signal "IN4")
		(26 "In12.Cu" signal "GND5")
		(28 "In13.Cu" signal "IN5")
		(30 "In14.Cu" signal "GND6")
		(32 "In15.Cu" signal "IN6")
		(34 "In16.Cu" signal "GND7")
		(2 "B.Cu" signal "BOTTOM")
		(9 "F.Adhes" user "F.Adhesive")
		(11 "B.Adhes" user "B.Adhesive")
		(13 "F.Paste" user "Package Geometry/Pastemask Top")
		(15 "B.Paste" user "Package Geometry/Pastemask Bottom")
		(5 "F.SilkS" user "Ref Des/Silkscreen Top")
		(7 "B.SilkS" user "Ref Des/Silkscreen Bottom")
		(1 "F.Mask" user "Board Geometry/Soldermask Top")
		(3 "B.Mask" user "Board Geometry/Soldermask Bottom")
		(17 "Dwgs.User" user "User.Drawings")
		(19 "Cmts.User" user "User.Comments")
		(21 "Eco1.User" user "User.Eco1")
		(23 "Eco2.User" user "User.Eco2")
		(25 "Edge.Cuts" user "Board Geometry/Outline")
		(27 "Margin" user)
		(31 "F.CrtYd" user "Package Geometry/Place Bound Top")
		(29 "B.CrtYd" user "Package Geometry/Place Bound Bottom")
		(35 "F.Fab" user "Ref Des/Assembly Top")
		(33 "B.Fab" user "Ref Des/Assembly Bottom")
	)
	(footprint ""
		(layer "B.Cu")
		(at 363.217206 -261.747762 90)
		(property "Reference" "C2137"
			(at 0 0 90)
			(layer "B.SilkS")
			(hide yes)
			(effects
				(font
					(size 1.27 1.27)
				)
				(justify mirror)
			)
		)
		(property "Value" ""
			(at 0 0 90)
			(layer "B.Fab")
			(effects
				(font
					(size 1.27 1.27)
				)
				(justify mirror)
			)
		)
		(duplicate_pad_numbers_are_jumpers no)
		(fp_line
			(start 0.7874 -0.4064)
			(end -0.7874 -0.4064)
			(stroke
				(width 0.1524)
				(type default)
			)
			(layer "B.SilkS")
		)
		(fp_line
			(start -0.7874 -0.4064)
			(end -0.7874 0.4064)
			(stroke
				(width 0.1524)
				(type default)
			)
			(layer "B.SilkS")
		)
		(fp_line
			(start 0.7874 0.4064)
			(end 0.7874 -0.4064)
			(stroke
				(width 0.1524)
				(type default)
			)
			(layer "B.SilkS")
		)
		(fp_line
			(start -0.7874 0.4064)
			(end 0.7874 0.4064)
			(stroke
				(width 0.1524)
				(type default)
			)
			(layer "B.SilkS")
		)
		(fp_line
			(start 0.67945 -0.305054)
			(end 0.12065 -0.305054)
			(stroke
				(width 0.1)
				(type default)
			)
			(layer "B.Fab")
		)
		(fp_line
			(start 0.12065 -0.305054)
			(end 0.12065 -0.2794)
			(stroke
				(width 0.1)
				(type default)
			)
			(layer "B.Fab")
		)
		(fp_line
			(start -0.12065 -0.3048)
			(end -0.67945 -0.3048)
			(stroke
				(width 0.1)
				(type default)
			)
			(layer "B.Fab")
		)
		(fp_line
			(start -0.67945 -0.3048)
			(end -0.67945 0.3048)
			(stroke
				(width 0.1)
				(type default)
			)
			(layer "B.Fab")
		)
		(fp_line
			(start 0.12065 -0.2794)
			(end -0.12065 -0.2794)
			(stroke
				(width 0.1)
				(type default)
			)
			(layer "B.Fab")
		)
		(fp_line
			(start -0.12065 -0.2794)
			(end -0.12065 -0.3048)
			(stroke
				(width 0.1)
				(type default)
			)
			(layer "B.Fab")
		)
		(fp_line
			(start 0.12065 0.2794)
			(end 0.12065 0.3048)
			(stroke
				(width 0.1)
				(type default)
			)
			(layer "B.Fab")
		)
		(fp_line
			(start -0.120396 0.2794)
			(end 0.12065 0.2794)
			(stroke
				(width 0.1)
				(type default)
			)
			(layer "B.Fab")
		)
		(fp_line
			(start 0.67945 0.3048)
			(end 0.67945 -0.305054)
			(stroke
				(width 0.1)
				(type default)
			)
			(layer "B.Fab")
		)
		(fp_line
			(start 0.12065 0.3048)
			(end 0.67945 0.3048)
			(stroke
				(width 0.1)
				(type default)
			)
			(layer "B.Fab")
		)
		(fp_line
			(start -0.120396 0.3048)
			(end -0.120396 0.2794)
			(stroke
				(width 0.1)
				(type default)
			)
			(layer "B.Fab")
		)
		(fp_line
			(start -0.67945 0.3048)
			(end -0.120396 0.3048)
			(stroke
				(width 0.1)
				(type default)
			)
			(layer "B.Fab")
		)
		(pad "1" smd circle
			(at 0.40005 0 270)
			(size 0 0)
			(layers "B.Cu" "B.Mask" "B.Paste")
			(net "PVDD11_S3_P0")
		)
		(pad "2" smd circle
			(at -0.40005 0 270)
			(size 0 0)
			(layers "B.Cu" "B.Mask" "B.Paste")
			(net "GND")
		)
	)
	(footprint ""
		(layer "B.Cu")
		(at 216.212674 -76.591668 180)
		(property "Reference" "R3211"
			(at 0 0 0)
			(layer "B.SilkS")
			(hide yes)
			(effects
				(font
					(size 1.27 1.27)
				)
				(justify mirror)
			)
		)
		(property "Value" ""
			(at 0 0 0)
			(layer "B.Fab")
			(effects
				(font
					(size 1.27 1.27)
				)
				(justify mirror)
			)
		)
		(duplicate_pad_numbers_are_jumpers no)
		(fp_line
			(start 0.7874 0.4064)
			(end 0.7874 -0.4064)
			(stroke
				(width 0.1524)
				(type default)
			)
			(layer "B.SilkS")
		)
		(fp_line
			(start 0.7874 -0.4064)
			(end -0.7874 -0.4064)
			(stroke
				(width 0.1524)
				(type default)
			)
			(layer "B.SilkS")
		)
		(fp_line
			(start -0.7874 0.4064)
			(end 0.7874 0.4064)
			(stroke
				(width 0.1524)
				(type default)
			)
			(layer "B.SilkS")
		)
		(fp_line
			(start -0.7874 -0.4064)
			(end -0.7874 0.4064)
			(stroke
				(width 0.1524)
				(type default)
			)
			(layer "B.SilkS")
		)
		(fp_line
			(start 0.67945 0.3048)
			(end 0.67945 -0.305054)
			(stroke
				(width 0.1)
				(type default)
			)
			(layer "B.Fab")
		)
		(fp_line
			(start 0.67945 -0.305054)
			(end 0.12065 -0.305054)
			(stroke
				(width 0.1)
				(type default)
			)
			(layer "B.Fab")
		)
		(fp_line
			(start 0.12065 0.3048)
			(end 0.67945 0.3048)
			(stroke
				(width 0.1)
				(type default)
			)
			(layer "B.Fab")
		)
		(fp_line
			(start 0.12065 0.2794)
			(end 0.12065 0.3048)
			(stroke
				(width 0.1)
				(type default)
			)
			(layer "B.Fab")
		)
		(fp_line
			(start 0.12065 -0.2794)
			(end -0.12065 -0.2794)
			(stroke
				(width 0.1)
				(type default)
			)
			(layer "B.Fab")
		)
		(fp_line
			(start 0.12065 -0.305054)
			(end 0.12065 -0.2794)
			(stroke
				(width 0.1)
				(type default)
			)
			(layer "B.Fab")
		)
		(fp_line
			(start -0.120396 0.3048)
			(end -0.120396 0.2794)
			(stroke
				(width 0.1)
				(type default)
			)
			(layer "B.Fab")
		)
		(fp_line
			(start -0.120396 0.2794)
			(end 0.12065 0.2794)
			(stroke
				(width 0.1)
				(type default)
			)
			(layer "B.Fab")
		)
		(fp_line
			(start -0.12065 -0.2794)
			(end -0.12065 -0.3048)
			(stroke
				(width 0.1)
				(type default)
			)
			(layer "B.Fab")
		)
		(fp_line
			(start -0.12065 -0.3048)
			(end -0.67945 -0.3048)
			(stroke
				(width 0.1)
				(type default)
			)
			(layer "B.Fab")
		)
		(fp_line
			(start -0.67945 0.3048)
			(end -0.120396 0.3048)
			(stroke
				(width 0.1)
				(type default)
			)
			(layer "B.Fab")
		)
		(fp_line
			(start -0.67945 -0.3048)
			(end -0.67945 0.3048)
			(stroke
				(width 0.1)
				(type default)
			)
			(layer "B.Fab")
		)
		(pad "1" smd circle
			(at 0.40005 0)
			(size 0 0)
			(layers "B.Cu" "B.Mask" "B.Paste")
			(net "NCSI_BMC_RXD0_R1")
		)
		(pad "2" smd circle
			(at -0.40005 0)
			(size 0 0)
			(layers "B.Cu" "B.Mask" "B.Paste")
			(net "RMII_OCP_BMC_RXD_0")
		)
	)
	(footprint ""
		(layer "B.Cu")
		(at 149.54631 -388.011162 -90)
		(property "Reference" "C411"
			(at 0 0 90)
			(layer "B.SilkS")
			(hide yes)
			(effects
				(font
					(size 1.27 1.27)
				)
				(justify mirror)
			)
		)
		(property "Value" ""
			(at 0 0 90)
			(layer "B.Fab")
			(effects
				(font
					(size 1.27 1.27)
				)
				(justify mirror)
			)
		)
		(duplicate_pad_numbers_are_jumpers no)
		(fp_line
			(start -0.299974 0.150114)
			(end 0.299974 0.150114)
			(stroke
				(width 0.1)
				(type default)
			)
			(layer "B.Fab")
		)
		(fp_line
			(start 0.299974 0.150114)
			(end 0.299974 -0.150114)
			(stroke
				(width 0.1)
				(type default)
			)
			(layer "B.Fab")
		)
		(fp_line
			(start -0.299974 -0.150114)
			(end -0.299974 0.150114)
			(stroke
				(width 0.1)
				(type default)
			)
			(layer "B.Fab")
		)
		(fp_line
			(start 0.299974 -0.150114)
			(end -0.299974 -0.150114)
			(stroke
				(width 0.1)
				(type default)
			)
			(layer "B.Fab")
		)
		(pad "1" smd rect
			(at 0.2667 0 90)
			(size 0.3048 0.381)
			(layers "B.Cu" "B.Mask" "B.Paste")
			(net "P0V9_CPU1_RT2_2A")
		)
		(pad "2" smd rect
			(at -0.2667 0 90)
			(size 0.3048 0.381)
			(layers "B.Cu" "B.Mask" "B.Paste")
			(net "GND")
		)
	)
)
